# S9S_MB_2U (Grand Teton) — schematic netlist excerpt (pin names and nets, part order shuffled) for the footprints in the layout excerpt that follows; sources: Cadence DE-HDL packaged netlist, KiCad conversion of 03242023_DA0F0TMBIJ0_F0T_Motherboard_J_brd_V01_OCP.brd

C770  Q_CAP_DIFFBUS  DIFF BUS_0.22UF 6.3V 20% X6S  pkg C0201  page 176 : \1\ = P5E_CPU1_PE2_TX_C_DN<1> ; \2\ = P5E_CPU1_PE2_TX_DN<1>
R4808  Q_RES  100K 1% EMPTY  pkg 0402LF  page 244 : A = PWRGD_DSW_PWROK ; B = GND
R980  Q_RES  560 1% CHIP  pkg 0402LF  page 236 : A = P3V3_AUX ; B = SMB_S3M_CPU1_3V3AUX_SDA

(kicad_pcb
	(version 20260206)
	(generator "pcbnew")
	(generator_version "10.0")
	(general
		(thickness 1.6)
		(legacy_teardrops no)
	)
	(paper "A4")
	(title_block
		(title "03242023_DA0F0TMBIJ0_F0T_Motherboard_J_brd_V01_OCP.brd")
		(comment 1 "Grand Teton / footprints 110-112 of 6105")
	)
	(layers
		(0 "F.Cu" signal "TOP")
		(4 "In1.Cu" signal "GND")
		(6 "In2.Cu" signal "IN1")
		(8 "In3.Cu" signal "GND1")
		(10 "In4.Cu" signal "IN2")
		(12 "In5.Cu" signal "GND2")
		(14 "In6.Cu" signal "IN3")
		(16 "In7.Cu" signal "GND3")
		(18 "In8.Cu" signal "VCC")
		(20 "In9.Cu" signal "VCC1")
		(22 "In10.Cu" signal "GND4")
		(24 "In11.Cu" signal "IN4")
		(26 "In12.Cu" signal "GND5")
		(28 "In13.Cu" signal "IN5")
		(30 "In14.Cu" signal "GND6")
		(32 "In15.Cu" signal "IN6")
		(34 "In16.Cu" signal "GND7")
		(2 "B.Cu" signal "BOTTOM")
		(9 "F.Adhes" user "F.Adhesive")
		(11 "B.Adhes" user "B.Adhesive")
		(13 "F.Paste" user "Package Geometry/Pastemask Top")
		(15 "B.Paste" user "Package Geometry/Pastemask Bottom")
		(5 "F.SilkS" user "Ref Des/Silkscreen Top")
		(7 "B.SilkS" user "Ref Des/Silkscreen Bottom")
		(1 "F.Mask" user "Board Geometry/Soldermask Top")
		(3 "B.Mask" user "Board Geometry/Soldermask Bottom")
		(17 "Dwgs.User" user "User.Drawings")
		(19 "Cmts.User" user "User.Comments")
		(21 "Eco1.User" user "User.Eco1")
		(23 "Eco2.User" user "User.Eco2")
		(25 "Edge.Cuts" user "Board Geometry/Outline")
		(27 "Margin" user)
		(31 "F.CrtYd" user "Package Geometry/Place Bound Top")
		(29 "B.CrtYd" user "Package Geometry/Place Bound Bottom")
		(35 "F.Fab" user "Ref Des/Assembly Top")
		(33 "B.Fab" user "Ref Des/Assembly Bottom")
	)
	(footprint ""
		(layer "F.Cu")
		(at 227.048568 -233.76255 180)
		(property "Reference" "R980"
			(at 0 0 180)
			(layer "F.SilkS")
			(hide yes)
			(effects
				(font
					(size 1.27 1.27)
				)
			)
		)
		(property "Value" ""
			(at 0 0 180)
			(layer "F.Fab")
			(effects
				(font
					(size 1.27 1.27)
				)
			)
		)
		(duplicate_pad_numbers_are_jumpers no)
		(fp_line
			(start 0.7874 0.4064)
			(end -0.7874 0.4064)
			(stroke
				(width 0.1524)
				(type default)
			)
			(layer "F.SilkS")
		)
		(fp_line
			(start 0.7874 -0.4064)
			(end 0.7874 0.4064)
			(stroke
				(width 0.1524)
				(type default)
			)
			(layer "F.SilkS")
		)
		(fp_line
			(start -0.7874 0.4064)
			(end -0.7874 -0.4064)
			(stroke
				(width 0.1524)
				(type default)
			)
			(layer "F.SilkS")
		)
		(fp_line
			(start -0.7874 -0.4064)
			(end 0.7874 -0.4064)
			(stroke
				(width 0.1524)
				(type default)
			)
			(layer "F.SilkS")
		)
		(fp_line
			(start 0.67945 0.3048)
			(end 0.120396 0.3048)
			(stroke
				(width 0.1)
				(type default)
			)
			(layer "F.Fab")
		)
		(fp_line
			(start 0.67945 -0.3048)
			(end 0.67945 0.3048)
			(stroke
				(width 0.1)
				(type default)
			)
			(layer "F.Fab")
		)
		(fp_line
			(start 0.12065 -0.2794)
			(end 0.12065 -0.3048)
			(stroke
				(width 0.1)
				(type default)
			)
			(layer "F.Fab")
		)
		(fp_line
			(start 0.12065 -0.3048)
			(end 0.67945 -0.3048)
			(stroke
				(width 0.1)
				(type default)
			)
			(layer "F.Fab")
		)
		(fp_line
			(start 0.120396 0.3048)
			(end 0.120396 0.2794)
			(stroke
				(width 0.1)
				(type default)
			)
			(layer "F.Fab")
		)
		(fp_line
			(start 0.120396 0.2794)
			(end -0.12065 0.2794)
			(stroke
				(width 0.1)
				(type default)
			)
			(layer "F.Fab")
		)
		(fp_line
			(start -0.12065 0.3048)
			(end -0.67945 0.3048)
			(stroke
				(width 0.1)
				(type default)
			)
			(layer "F.Fab")
		)
		(fp_line
			(start -0.12065 0.2794)
			(end -0.12065 0.3048)
			(stroke
				(width 0.1)
				(type default)
			)
			(layer "F.Fab")
		)
		(fp_line
			(start -0.12065 -0.2794)
			(end 0.12065 -0.2794)
			(stroke
				(width 0.1)
				(type default)
			)
			(layer "F.Fab")
		)
		(fp_line
			(start -0.12065 -0.305054)
			(end -0.12065 -0.2794)
			(stroke
				(width 0.1)
				(type default)
			)
			(layer "F.Fab")
		)
		(fp_line
			(start -0.67945 0.3048)
			(end -0.67945 -0.305054)
			(stroke
				(width 0.1)
				(type default)
			)
			(layer "F.Fab")
		)
		(fp_line
			(start -0.67945 -0.305054)
			(end -0.12065 -0.305054)
			(stroke
				(width 0.1)
				(type default)
			)
			(layer "F.Fab")
		)
		(pad "1" smd circle
			(at -0.40005 0 180)
			(size 0 0)
			(layers "F.Cu" "F.Mask" "F.Paste")
			(net "P3V3_AUX")
		)
		(pad "2" smd circle
			(at 0.40005 0 180)
			(size 0 0)
			(layers "F.Cu" "F.Mask" "F.Paste")
			(net "SMB_S3M_CPU1_3V3AUX_SDA")
		)
	)
	(footprint ""
		(layer "F.Cu")
		(at 163.929314 -402.371052 -90)
		(property "Reference" "C770"
			(at 0 0 270)
			(layer "F.SilkS")
			(hide yes)
			(effects
				(font
					(size 1.27 1.27)
				)
			)
		)
		(property "Value" ""
			(at 0 0 270)
			(layer "F.Fab")
			(effects
				(font
					(size 1.27 1.27)
				)
			)
		)
		(duplicate_pad_numbers_are_jumpers no)
		(fp_line
			(start -0.299974 0.150114)
			(end -0.299974 -0.150114)
			(stroke
				(width 0.1)
				(type default)
			)
			(layer "F.Fab")
		)
		(fp_line
			(start 0.299974 0.150114)
			(end -0.299974 0.150114)
			(stroke
				(width 0.1)
				(type default)
			)
			(layer "F.Fab")
		)
		(fp_line
			(start -0.299974 -0.150114)
			(end 0.299974 -0.150114)
			(stroke
				(width 0.1)
				(type default)
			)
			(layer "F.Fab")
		)
		(fp_line
			(start 0.299974 -0.150114)
			(end 0.299974 0.150114)
			(stroke
				(width 0.1)
				(type default)
			)
			(layer "F.Fab")
		)
		(pad "1" smd rect
			(at -0.2667 0 270)
			(size 0.3048 0.381)
			(layers "F.Cu" "F.Mask" "F.Paste")
			(net "P5E_CPU1_PE2_TX_C_DN<1>")
		)
		(pad "2" smd rect
			(at 0.2667 0 270)
			(size 0.3048 0.381)
			(layers "F.Cu" "F.Mask" "F.Paste")
			(net "P5E_CPU1_PE2_TX_DN<1>")
		)
	)
	(footprint ""
		(layer "F.Cu")
		(at 209.743802 -125.476)
		(property "Reference" "R4808"
			(at 0 0 0)
			(layer "F.SilkS")
			(hide yes)
			(effects
				(font
					(size 1.27 1.27)
				)
			)
		)
		(property "Value" ""
			(at 0 0 0)
			(layer "F.Fab")
			(effects
				(font
					(size 1.27 1.27)
				)
			)
		)
		(duplicate_pad_numbers_are_jumpers no)
		(fp_line
			(start -0.7874 -0.4064)
			(end 0.7874 -0.4064)
			(stroke
				(width 0.1524)
				(type default)
			)
			(layer "F.SilkS")
		)
		(fp_line
			(start -0.7874 0.4064)
			(end -0.7874 -0.4064)
			(stroke
				(width 0.1524)
				(type default)
			)
			(layer "F.SilkS")
		)
		(fp_line
			(start 0.7874 -0.4064)
			(end 0.7874 0.4064)
			(stroke
				(width 0.1524)
				(type default)
			)
			(layer "F.SilkS")
		)
		(fp_line
			(start 0.7874 0.4064)
			(end -0.7874 0.4064)
			(stroke
				(width 0.1524)
				(type default)
			)
			(layer "F.SilkS")
		)
		(fp_line
			(start -0.67945 -0.305054)
			(end -0.12065 -0.305054)
			(stroke
				(width 0.1)
				(type default)
			)
			(layer "F.Fab")
		)
		(fp_line
			(start -0.67945 0.3048)
			(end -0.67945 -0.305054)
			(stroke
				(width 0.1)
				(type default)
			)
			(layer "F.Fab")
		)
		(fp_line
			(start -0.12065 -0.305054)
			(end -0.12065 -0.2794)
			(stroke
				(width 0.1)
				(type default)
			)
			(layer "F.Fab")
		)
		(fp_line
			(start -0.12065 -0.2794)
			(end 0.12065 -0.2794)
			(stroke
				(width 0.1)
				(type default)
			)
			(layer "F.Fab")
		)
		(fp_line
			(start -0.12065 0.2794)
			(end -0.12065 0.3048)
			(stroke
				(width 0.1)
				(type default)
			)
			(layer "F.Fab")
		)
		(fp_line
			(start -0.12065 0.3048)
			(end -0.67945 0.3048)
			(stroke
				(width 0.1)
				(type default)
			)
			(layer "F.Fab")
		)
		(fp_line
			(start 0.120396 0.2794)
			(end -0.12065 0.2794)
			(stroke
				(width 0.1)
				(type default)
			)
			(layer "F.Fab")
		)
		(fp_line
			(start 0.120396 0.3048)
			(end 0.120396 0.2794)
			(stroke
				(width 0.1)
				(type default)
			)
			(layer "F.Fab")
		)
		(fp_line
			(start 0.12065 -0.3048)
			(end 0.67945 -0.3048)
			(stroke
				(width 0.1)
				(type default)
			)
			(layer "F.Fab")
		)
		(fp_line
			(start 0.12065 -0.2794)
			(end 0.12065 -0.3048)
			(stroke
				(width 0.1)
				(type default)
			)
			(layer "F.Fab")
		)
		(fp_line
			(start 0.67945 -0.3048)
			(end 0.67945 0.3048)
			(stroke
				(width 0.1)
				(type default)
			)
			(layer "F.Fab")
		)
		(fp_line
			(start 0.67945 0.3048)
			(end 0.120396 0.3048)
			(stroke
				(width 0.1)
				(type default)
			)
			(layer "F.Fab")
		)
		(pad "1" smd circle
			(at -0.40005 0)
			(size 0 0)
			(layers "F.Cu" "F.Mask" "F.Paste")
			(net "PWRGD_DSW_PWROK")
		)
		(pad "2" smd circle
			(at 0.40005 0)
			(size 0 0)
			(layers "F.Cu" "F.Mask" "F.Paste")
			(net "GND")
		)
	)
)
